(kicad_pcb
	(version 20241229)
	(generator "pcbnew")
	(generator_version "9.0")
	(general
		(thickness 1.61)
		(legacy_teardrops no)
	)
	(paper "A3")
	(title_block
		(title "RDIMM DDR5 Tester")
		(date "2026-05-21")
		(rev "2.2.0")
		(company "Antmicro")
		(comment 9 "footprints 608-612 of 796")
	)
	(layers
		(0 "F.Cu" signal)
		(4 "In1.Cu" power)
		(6 "In2.Cu" mixed)
		(8 "In3.Cu" power)
		(10 "In4.Cu" mixed)
		(12 "In5.Cu" power)
		(14 "In6.Cu" mixed)
		(16 "In7.Cu" power)
		(18 "In8.Cu" power)
		(20 "In9.Cu" mixed)
		(22 "In10.Cu" power)
		(2 "B.Cu" signal)
		(9 "F.Adhes" user "F.Adhesive")
		(11 "B.Adhes" user "B.Adhesive")
		(13 "F.Paste" user)
		(15 "B.Paste" user)
		(5 "F.SilkS" user "F.Silkscreen")
		(7 "B.SilkS" user "B.Silkscreen")
		(1 "F.Mask" user)
		(3 "B.Mask" user)
		(17 "Dwgs.User" user "User.Drawings")
		(19 "Cmts.User" user "User.Comments")
		(21 "Eco1.User" user "User.Eco1")
		(23 "Eco2.User" user "User.Eco2")
		(25 "Edge.Cuts" user)
		(27 "Margin" user)
		(31 "F.CrtYd" user "F.Courtyard")
		(29 "B.CrtYd" user "B.Courtyard")
		(35 "F.Fab" user)
		(33 "B.Fab" user)
	)
	(footprint "antmicro-footprints:R_0402_1005Metric"
		(layer "B.Cu")
		(at 247.475 186.299)
		(descr "Resistor SMD 0402")
		(tags "resistor SMD 0402")
		(property "Reference" "R97"
			(at 1.47 0.551 0)
			(layer "B.SilkS")
			(effects
				(font
					(size 0.7 0.7)
					(thickness 0.15)
				)
				(justify right bottom mirror)
			)
		)
		(property "Value" "R_4k7_0402"
			(at -1.011843 -1.772047 0)
			(layer "B.Fab")
			(effects
				(font
					(size 0.7 0.7)
					(thickness 0.15)
				)
				(justify right bottom mirror)
			)
		)
		(property "Datasheet" "https://www.bourns.com/docs/product-datasheets/cr.pdf"
			(at 0 0 0)
			(layer "F.Fab")
			(hide yes)
			(effects
				(font
					(size 1.27 1.27)
					(thickness 0.15)
				)
			)
		)
		(property "MPN" "CR0402-FX-4701GLF"
			(at 0 0 0)
			(unlocked yes)
			(layer "B.Fab")
			(hide yes)
			(effects
				(font
					(size 1 1)
					(thickness 0.15)
				)
				(justify mirror)
			)
		)
		(property "Manufacturer" "Bourns"
			(at 0 0 0)
			(unlocked yes)
			(layer "B.Fab")
			(hide yes)
			(effects
				(font
					(size 1 1)
					(thickness 0.15)
				)
				(justify mirror)
			)
		)
		(property "License" "Apache-2.0"
			(at 0 0 0)
			(unlocked yes)
			(layer "B.Fab")
			(hide yes)
			(effects
				(font
					(size 1 1)
					(thickness 0.15)
				)
				(justify mirror)
			)
		)
		(property "Author" "Antmicro"
			(at 0 0 0)
			(unlocked yes)
			(layer "B.Fab")
			(hide yes)
			(effects
				(font
					(size 1 1)
					(thickness 0.15)
				)
				(justify mirror)
			)
		)
		(property "Val" "4k7"
			(at 0 0 0)
			(unlocked yes)
			(layer "B.Fab")
			(hide yes)
			(effects
				(font
					(size 1 1)
					(thickness 0.15)
				)
				(justify mirror)
			)
		)
		(property "Tolerance" "1%"
			(at 0 0 0)
			(unlocked yes)
			(layer "B.Fab")
			(hide yes)
			(effects
				(font
					(size 1 1)
					(thickness 0.15)
				)
				(justify mirror)
			)
		)
		(sheetname "/I^{2}C + I3C/")
		(sheetfile "i2c.kicad_sch")
		(attr smd)
		(fp_rect
			(start -0.925 0.47)
			(end 0.925 -0.47)
			(stroke
				(width 0.05)
				(type default)
			)
			(fill no)
			(layer "B.CrtYd")
		)
		(fp_rect
			(start -0.5 0.25)
			(end 0.5 -0.25)
			(stroke
				(width 0.15)
				(type solid)
			)
			(fill no)
			(layer "B.Fab")
		)
		(fp_text user "Author: Antmicro"
			(at -0.95 -4.169 180)
			(layer "B.Fab")
			(effects
				(font
					(size 0.7 0.7)
					(thickness 0.15)
				)
				(justify left bottom mirror)
			)
		)
		(fp_text user "${REFERENCE}"
			(at -0.95 -3.168 180)
			(layer "B.Fab")
			(effects
				(font
					(size 0.7 0.7)
					(thickness 0.15)
				)
				(justify left bottom mirror)
			)
		)
		(fp_text user "License: Apache-2.0"
			(at -0.95 -5.169 180)
			(layer "B.Fab")
			(effects
				(font
					(size 0.7 0.7)
					(thickness 0.15)
				)
				(justify left bottom mirror)
			)
		)
		(pad "1" smd roundrect
			(at -0.48 0)
			(size 0.59 0.64)
			(layers "B.Cu" "B.Mask" "B.Paste")
			(roundrect_rratio 0.25)
			(net 771 "/FPGA banks HD/FPGA_I3C.SCL")
			(pintype "passive")
		)
		(pad "2" smd roundrect
			(at 0.48 0)
			(size 0.59 0.64)
			(layers "B.Cu" "B.Mask" "B.Paste")
			(roundrect_rratio 0.25)
			(net 662 "Net-(Q22-D)")
			(pintype "passive")
		)
	)
	(footprint "antmicro-footprints:C_0805_2012Metric"
		(layer "B.Cu")
		(at 203.5 154.4 90)
		(descr "Capacitor SMD 0805")
		(tags "capacitor SMD 0805")
		(property "Reference" "C242"
			(at -1.91 1.91 90)
			(layer "B.SilkS")
			(effects
				(font
					(size 0.7 0.7)
					(thickness 0.15)
				)
				(justify right bottom mirror)
			)
		)
		(property "Value" "C_100u_0805"
			(at -2.055717 -1.963152 90)
			(layer "B.Fab")
			(effects
				(font
					(size 0.7 0.7)
					(thickness 0.15)
				)
				(justify right bottom mirror)
			)
		)
		(property "Datasheet" "https://www.murata.com/products/productdetail?partno=GRM21BR60J107ME15%23"
			(at 0 0 90)
			(layer "F.Fab")
			(hide yes)
			(effects
				(font
					(size 1.27 1.27)
					(thickness 0.15)
				)
			)
		)
		(property "MPN" "GRM21BR60J107ME15L"
			(at 0 0 90)
			(unlocked yes)
			(layer "B.Fab")
			(hide yes)
			(effects
				(font
					(size 1 1)
					(thickness 0.15)
				)
				(justify mirror)
			)
		)
		(property "Manufacturer" "Murata"
			(at 0 0 90)
			(unlocked yes)
			(layer "B.Fab")
			(hide yes)
			(effects
				(font
					(size 1 1)
					(thickness 0.15)
				)
				(justify mirror)
			)
		)
		(property "License" "Apache-2.0"
			(at 0 0 90)
			(unlocked yes)
			(layer "B.Fab")
			(hide yes)
			(effects
				(font
					(size 1 1)
					(thickness 0.15)
				)
				(justify mirror)
			)
		)
		(property "Author" "Antmicro"
			(at 0 0 90)
			(unlocked yes)
			(layer "B.Fab")
			(hide yes)
			(effects
				(font
					(size 1 1)
					(thickness 0.15)
				)
				(justify mirror)
			)
		)
		(property "Val" "100u"
			(at 0 0 90)
			(unlocked yes)
			(layer "B.Fab")
			(hide yes)
			(effects
				(font
					(size 1 1)
					(thickness 0.15)
				)
				(justify mirror)
			)
		)
		(property "Voltage" ""
			(at 0 0 90)
			(unlocked yes)
			(layer "B.Fab")
			(hide yes)
			(effects
				(font
					(size 1 1)
					(thickness 0.15)
				)
				(justify mirror)
			)
		)
		(property "Dielectric" ""
			(at 0 0 90)
			(unlocked yes)
			(layer "B.Fab")
			(hide yes)
			(effects
				(font
					(size 1 1)
					(thickness 0.15)
				)
				(justify mirror)
			)
		)
		(property "Public" "False"
			(at 0 0 90)
			(unlocked yes)
			(layer "B.Fab")
			(hide yes)
			(effects
				(font
					(size 1 1)
					(thickness 0.15)
				)
				(justify mirror)
			)
		)
		(sheetname "/FPGA power/")
		(sheetfile "fpga-power.kicad_sch")
		(attr smd)
		(fp_line
			(start -0.3 -0.7)
			(end 0.3 -0.7)
			(stroke
				(width 0.15)
				(type solid)
			)
			(layer "B.SilkS")
		)
		(fp_line
			(start -0.3 0.7)
			(end 0.3 0.7)
			(stroke
				(width 0.15)
				(type solid)
			)
			(layer "B.SilkS")
		)
		(fp_rect
			(start 1.95 0.9)
			(end -1.95 -0.9)
			(stroke
				(width 0.05)
				(type default)
			)
			(fill no)
			(layer "B.CrtYd")
		)
		(fp_rect
			(start -0.95 0.675)
			(end 0.95 -0.675)
			(stroke
				(width 0.15)
				(type solid)
			)
			(fill no)
			(layer "B.Fab")
		)
		(fp_text user "Author: Antmicro"
			(at -1.9 -5.947 270)
			(layer "B.Fab")
			(effects
				(font
					(size 0.7 0.7)
					(thickness 0.15)
				)
				(justify left bottom mirror)
			)
		)
		(fp_text user "License: Apache-2.0"
			(at -1.9 -4.947 270)
			(layer "B.Fab")
			(effects
				(font
					(size 0.7 0.7)
					(thickness 0.15)
				)
				(justify left bottom mirror)
			)
		)
		(fp_text user "${REFERENCE}"
			(at -1.9 -3.947 270)
			(layer "B.Fab")
			(effects
				(font
					(size 0.7 0.7)
					(thickness 0.15)
				)
				(justify left bottom mirror)
			)
		)
		(pad "1" smd roundrect
			(at -1.1 0 90)
			(size 1.2 1.3)
			(layers "B.Cu" "B.Mask" "B.Paste")
			(roundrect_rratio 0.25)
			(net 1 "GND")
			(pintype "passive")
		)
		(pad "2" smd roundrect
			(at 1.1 0 90)
			(size 1.2 1.3)
			(layers "B.Cu" "B.Mask" "B.Paste")
			(roundrect_rratio 0.25)
			(net 553 "+0V85")
			(pintype "passive")
		)
	)
	(footprint "antmicro-footprints:C_0402_1005Metric"
		(layer "B.Cu")
		(at 122.95 152.61)
		(descr "Capacitor SMD 0402")
		(tags "capacitor SMD 0402")
		(property "Reference" "C306"
			(at 2.44 1.504 0)
			(layer "B.SilkS")
			(effects
				(font
					(size 0.7 0.7)
					(thickness 0.15)
				)
				(justify right bottom mirror)
			)
		)
		(property "Value" "C_100n_0402"
			(at -1.022927 -2.155213 0)
			(layer "B.Fab")
			(effects
				(font
					(size 0.7 0.7)
					(thickness 0.15)
				)
				(justify right bottom mirror)
			)
		)
		(property "Datasheet" "https://www.murata.com/products/productdetail?partno=GRM155R61H104KE14%23"
			(at 0 0 0)
			(layer "F.Fab")
			(hide yes)
			(effects
				(font
					(size 1.27 1.27)
					(thickness 0.15)
				)
			)
		)
		(property "Manufacturer" "Murata"
			(at 0 0 0)
			(unlocked yes)
			(layer "B.Fab")
			(hide yes)
			(effects
				(font
					(size 1 1)
					(thickness 0.15)
				)
				(justify mirror)
			)
		)
		(property "MPN" "GRM155R61H104KE14D"
			(at 0 0 0)
			(unlocked yes)
			(layer "B.Fab")
			(hide yes)
			(effects
				(font
					(size 1 1)
					(thickness 0.15)
				)
				(justify mirror)
			)
		)
		(property "Val" "100n"
			(at 0 0 0)
			(unlocked yes)
			(layer "B.Fab")
			(hide yes)
			(effects
				(font
					(size 1 1)
					(thickness 0.15)
				)
				(justify mirror)
			)
		)
		(property "License" "Apache-2.0"
			(at 0 0 0)
			(unlocked yes)
			(layer "B.Fab")
			(hide yes)
			(effects
				(font
					(size 1 1)
					(thickness 0.15)
				)
				(justify mirror)
			)
		)
		(property "Author" "Antmicro"
			(at 0 0 0)
			(unlocked yes)
			(layer "B.Fab")
			(hide yes)
			(effects
				(font
					(size 1 1)
					(thickness 0.15)
				)
				(justify mirror)
			)
		)
		(property "Voltage" "50V"
			(at 0 0 0)
			(unlocked yes)
			(layer "B.Fab")
			(hide yes)
			(effects
				(font
					(size 1 1)
					(thickness 0.15)
				)
				(justify mirror)
			)
		)
		(property "Dielectric" "X5R"
			(at 0 0 0)
			(unlocked yes)
			(layer "B.Fab")
			(hide yes)
			(effects
				(font
					(size 1 1)
					(thickness 0.15)
				)
				(justify mirror)
			)
		)
		(sheetname "/FPGA MGT Interface/")
		(sheetfile "fpga-mgt.kicad_sch")
		(attr smd)
		(fp_rect
			(start -0.925 0.47)
			(end 0.925 -0.47)
			(stroke
				(width 0.05)
				(type default)
			)
			(fill no)
			(layer "B.CrtYd")
		)
		(fp_line
			(start -0.494 -0.248)
			(end -0.494 0.25)
			(stroke
				(width 0.15)
				(type solid)
			)
			(layer "B.Fab")
		)
		(fp_line
			(start -0.494 0.25)
			(end 0.504 0.25)
			(stroke
				(width 0.15)
				(type solid)
			)
			(layer "B.Fab")
		)
		(fp_line
			(start 0.504 -0.248)
			(end -0.494 -0.248)
			(stroke
				(width 0.15)
				(type solid)
			)
			(layer "B.Fab")
		)
		(fp_line
			(start 0.504 0.25)
			(end 0.504 -0.248)
			(stroke
				(width 0.15)
				(type solid)
			)
			(layer "B.Fab")
		)
		(fp_text user "${REFERENCE}"
			(at -0.939 -4.599 180)
			(layer "B.Fab")
			(effects
				(font
					(size 0.7 0.7)
					(thickness 0.15)
				)
				(justify left bottom mirror)
			)
		)
		(fp_text user "License: Apache-2.0"
			(at -0.939 -5.799 180)
			(layer "B.Fab")
			(effects
				(font
					(size 0.7 0.7)
					(thickness 0.15)
				)
				(justify left bottom mirror)
			)
		)
		(fp_text user "Author: Antmicro"
			(at -0.939 -3.399 180)
			(layer "B.Fab")
			(effects
				(font
					(size 0.7 0.7)
					(thickness 0.15)
				)
				(justify left bottom mirror)
			)
		)
		(pad "1" smd roundrect
			(at -0.48 0)
			(size 0.59 0.64)
			(layers "B.Cu" "B.Mask" "B.Paste")
			(roundrect_rratio 0.25)
			(net 349 "/FPGA MGT Interface/HDMI_IN.D0_N")
			(pintype "passive")
		)
		(pad "2" smd roundrect
			(at 0.48 0)
			(size 0.59 0.64)
			(layers "B.Cu" "B.Mask" "B.Paste")
			(roundrect_rratio 0.25)
			(net 652 "/FPGA MGT Interface/HDMI_FPGA.RX0_N")
			(pintype "passive")
		)
	)
	(footprint "antmicro-footprints:C_0402_1005Metric_EIA"
		(layer "B.Cu")
		(at 180.5 147)
		(descr "Capacitor SMD 0402 (1005 Metric), square (rectangular) end terminal, IPC_7351 nominal, (Body size source: IPC-SM-782 page 76, https://www.pcb-3d.com/wordpress/wp-content/uploads/ipc-sm-782a_amendment_1_and_2.pdf)")
		(tags "capacitor 0402")
		(property "Reference" "C89"
			(at -3.15 0.525 0)
			(layer "B.SilkS")
			(effects
				(font
					(size 0.7 0.7)
					(thickness 0.15)
				)
				(justify right bottom mirror)
			)
		)
		(property "Value" "C_100n_0402"
			(at 0 -1.169 0)
			(layer "B.Fab")
			(effects
				(font
					(size 0.7 0.7)
					(thickness 0.15)
				)
				(justify right bottom mirror)
			)
		)
		(property "Datasheet" "https://www.murata.com/products/productdetail?partno=GRM155R61H104KE14%23"
			(at 0 0 0)
			(layer "F.Fab")
			(hide yes)
			(effects
				(font
					(size 1.27 1.27)
					(thickness 0.15)
				)
			)
		)
		(property "MPN" "GRM155R61H104KE14D"
			(at 0 0 0)
			(unlocked yes)
			(layer "B.Fab")
			(hide yes)
			(effects
				(font
					(size 1 1)
					(thickness 0.15)
				)
				(justify mirror)
			)
		)
		(property "Manufacturer" "Murata"
			(at 0 0 0)
			(unlocked yes)
			(layer "B.Fab")
			(hide yes)
			(effects
				(font
					(size 1 1)
					(thickness 0.15)
				)
				(justify mirror)
			)
		)
		(property "License" "Apache-2.0"
			(at 0 0 0)
			(unlocked yes)
			(layer "B.Fab")
			(hide yes)
			(effects
				(font
					(size 1 1)
					(thickness 0.15)
				)
				(justify mirror)
			)
		)
		(property "Author" "Antmicro"
			(at 0 0 0)
			(unlocked yes)
			(layer "B.Fab")
			(hide yes)
			(effects
				(font
					(size 1 1)
					(thickness 0.15)
				)
				(justify mirror)
			)
		)
		(property "Val" "100n"
			(at 0 0 0)
			(unlocked yes)
			(layer "B.Fab")
			(hide yes)
			(effects
				(font
					(size 1 1)
					(thickness 0.15)
				)
				(justify mirror)
			)
		)
		(property "Voltage" "50V"
			(at 0 0 0)
			(unlocked yes)
			(layer "B.Fab")
			(hide yes)
			(effects
				(font
					(size 1 1)
					(thickness 0.15)
				)
				(justify mirror)
			)
		)
		(property "Dielectric" "X5R"
			(at 0 0 0)
			(unlocked yes)
			(layer "B.Fab")
			(hide yes)
			(effects
				(font
					(size 1 1)
					(thickness 0.15)
				)
				(justify mirror)
			)
		)
		(sheetname "/FPGA power/")
		(sheetfile "fpga-power.kicad_sch")
		(attr smd)
		(fp_rect
			(start -0.95 0.45)
			(end 0.95 -0.45)
			(stroke
				(width 0.05)
				(type default)
			)
			(fill no)
			(layer "B.CrtYd")
		)
		(fp_line
			(start -0.5 -0.248)
			(end -0.5 0.25)
			(stroke
				(width 0.15)
				(type solid)
			)
			(layer "B.Fab")
		)
		(fp_line
			(start -0.5 0.25)
			(end 0.498 0.25)
			(stroke
				(width 0.15)
				(type solid)
			)
			(layer "B.Fab")
		)
		(fp_line
			(start 0.498 -0.248)
			(end -0.5 -0.248)
			(stroke
				(width 0.15)
				(type solid)
			)
			(layer "B.Fab")
		)
		(fp_line
			(start 0.498 0.25)
			(end 0.498 -0.248)
			(stroke
				(width 0.15)
				(type solid)
			)
			(layer "B.Fab")
		)
		(fp_text user "License: Apache-2.0"
			(at -0.9656 -4.369 180)
			(layer "B.Fab")
			(effects
				(font
					(size 0.7 0.7)
					(thickness 0.15)
				)
				(justify left bottom mirror)
			)
		)
		(fp_text user "${REFERENCE}"
			(at -0.9656 -3.169 180)
			(layer "B.Fab")
			(effects
				(font
					(size 0.7 0.7)
					(thickness 0.15)
				)
				(justify left bottom mirror)
			)
		)
		(fp_text user "Author: Antmicro"
			(at -0.9656 -5.569 180)
			(layer "B.Fab")
			(effects
				(font
					(size 0.7 0.7)
					(thickness 0.15)
				)
				(justify left bottom mirror)
			)
		)
		(pad "1" smd roundrect
			(at -0.5 0 270)
			(size 0.6 0.6)
			(layers "B.Cu" "B.Mask" "B.Paste")
			(roundrect_rratio 0.25)
			(net 1 "GND")
			(pintype "passive")
		)
		(pad "2" smd roundrect
			(at 0.498 0)
			(size 0.6 0.6)
			(layers "B.Cu" "B.Mask" "B.Paste")
			(roundrect_rratio 0.25)
			(net 797 "+1V8")
			(pintype "passive")
		)
	)
	(footprint "antmicro-footprints:R_0402_1005Metric"
		(layer "B.Cu")
		(at 116.26 164.45 -90)
		(descr "Resistor SMD 0402")
		(tags "resistor SMD 0402")
		(property "Reference" "R86"
			(at -1 -1.54 90)
			(layer "B.SilkS")
			(effects
				(font
					(size 0.7 0.7)
					(thickness 0.15)
				)
				(justify left bottom mirror)
			)
		)
		(property "Value" "R_10k_0402"
			(at -1.011843 -1.772047 90)
			(layer "B.Fab")
			(effects
				(font
					(size 0.7 0.7)
					(thickness 0.15)
				)
				(justify left bottom mirror)
			)
		)
		(property "Datasheet" "https://www.bourns.com/docs/product-datasheets/cr.pdf"
			(at 0 0 270)
			(layer "F.Fab")
			(hide yes)
			(effects
				(font
					(size 1.27 1.27)
					(thickness 0.15)
				)
			)
		)
		(property "MPN" "CR0402-FX-1002GLF"
			(at 0 0 270)
			(unlocked yes)
			(layer "B.Fab")
			(hide yes)
			(effects
				(font
					(size 1 1)
					(thickness 0.15)
				)
				(justify mirror)
			)
		)
		(property "Manufacturer" "Bourns"
			(at 0 0 270)
			(unlocked yes)
			(layer "B.Fab")
			(hide yes)
			(effects
				(font
					(size 1 1)
					(thickness 0.15)
				)
				(justify mirror)
			)
		)
		(property "License" "Apache-2.0"
			(at 0 0 270)
			(unlocked yes)
			(layer "B.Fab")
			(hide yes)
			(effects
				(font
					(size 1 1)
					(thickness 0.15)
				)
				(justify mirror)
			)
		)
		(property "Author" "Antmicro"
			(at 0 0 270)
			(unlocked yes)
			(layer "B.Fab")
			(hide yes)
			(effects
				(font
					(size 1 1)
					(thickness 0.15)
				)
				(justify mirror)
			)
		)
		(property "Val" "10k"
			(at 0 0 270)
			(unlocked yes)
			(layer "B.Fab")
			(hide yes)
			(effects
				(font
					(size 1 1)
					(thickness 0.15)
				)
				(justify mirror)
			)
		)
		(property "Tolerance" "1%"
			(at 0 0 270)
			(unlocked yes)
			(layer "B.Fab")
			(hide yes)
			(effects
				(font
					(size 1 1)
					(thickness 0.15)
				)
				(justify mirror)
			)
		)
		(sheetname "/HDMI + SD Card/")
		(sheetfile "hdmi-sd-card.kicad_sch")
		(attr smd)
		(fp_rect
			(start -0.925 0.47)
			(end 0.925 -0.47)
			(stroke
				(width 0.05)
				(type default)
			)
			(fill no)
			(layer "B.CrtYd")
		)
		(fp_rect
			(start -0.5 0.25)
			(end 0.5 -0.25)
			(stroke
				(width 0.15)
				(type solid)
			)
			(fill no)
			(layer "B.Fab")
		)
		(fp_text user "License: Apache-2.0"
			(at -0.95 -5.169 90)
			(layer "B.Fab")
			(effects
				(font
					(size 0.7 0.7)
					(thickness 0.15)
				)
				(justify left bottom mirror)
			)
		)
		(fp_text user "Author: Antmicro"
			(at -0.95 -4.169 90)
			(layer "B.Fab")
			(effects
				(font
					(size 0.7 0.7)
					(thickness 0.15)
				)
				(justify left bottom mirror)
			)
		)
		(fp_text user "${REFERENCE}"
			(at -0.95 -3.168 90)
			(layer "B.Fab")
			(effects
				(font
					(size 0.7 0.7)
					(thickness 0.15)
				)
				(justify left bottom mirror)
			)
		)
		(pad "1" smd roundrect
			(at -0.48 0 270)
			(size 0.59 0.64)
			(layers "B.Cu" "B.Mask" "B.Paste")
			(roundrect_rratio 0.25)
			(net 507 "HDMI_IN_CD")
			(pintype "passive")
		)
		(pad "2" smd roundrect
			(at 0.48 0 270)
			(size 0.59 0.64)
			(layers "B.Cu" "B.Mask" "B.Paste")
			(roundrect_rratio 0.25)
			(net 151 "+3V3")
			(pintype "passive")
		)
	)
)
